# S9S_MB_2U (Grand Teton) — schematic netlist excerpt (pin names and nets, part order shuffled) for the footprints in the layout excerpt that follows; sources: Cadence DE-HDL packaged netlist, KiCad conversion of 03242023_DA0F0TMBIJ0_F0T_Motherboard_J_brd_V01_OCP.brd

C1  Q_CAP  10UF 6.3V 20% X6S  pkg C0402  page 37 : A = P3V3_AUX ; B = GND
C89  Q_CAP  10UF 16V 10% X6S  pkg C0805  page 108 : A = P12V_S3_AUX_CPU1_NVDIMM ; B = GND
R164  Q_RES  0 5% CHIP  pkg 0402LF  page 124 : A = PWRGD_DRAMPWRGD_CPU0_EF_R_LVC1 ; B = PWRGD_DRAMPWRGD_CPU0_EF_LVC1_R2

(kicad_pcb
	(version 20260206)
	(generator "pcbnew")
	(generator_version "10.0")
	(general
		(thickness 1.6)
		(legacy_teardrops no)
	)
	(paper "A4")
	(title_block
		(title "03242023_DA0F0TMBIJ0_F0T_Motherboard_J_brd_V01_OCP.brd")
		(comment 1 "Grand Teton / footprints 4824-4826 of 6105")
	)
	(layers
		(0 "F.Cu" signal "TOP")
		(4 "In1.Cu" signal "GND")
		(6 "In2.Cu" signal "IN1")
		(8 "In3.Cu" signal "GND1")
		(10 "In4.Cu" signal "IN2")
		(12 "In5.Cu" signal "GND2")
		(14 "In6.Cu" signal "IN3")
		(16 "In7.Cu" signal "GND3")
		(18 "In8.Cu" signal "VCC")
		(20 "In9.Cu" signal "VCC1")
		(22 "In10.Cu" signal "GND4")
		(24 "In11.Cu" signal "IN4")
		(26 "In12.Cu" signal "GND5")
		(28 "In13.Cu" signal "IN5")
		(30 "In14.Cu" signal "GND6")
		(32 "In15.Cu" signal "IN6")
		(34 "In16.Cu" signal "GND7")
		(2 "B.Cu" signal "BOTTOM")
		(9 "F.Adhes" user "F.Adhesive")
		(11 "B.Adhes" user "B.Adhesive")
		(13 "F.Paste" user "Package Geometry/Pastemask Top")
		(15 "B.Paste" user "Package Geometry/Pastemask Bottom")
		(5 "F.SilkS" user "Ref Des/Silkscreen Top")
		(7 "B.SilkS" user "Ref Des/Silkscreen Bottom")
		(1 "F.Mask" user "Board Geometry/Soldermask Top")
		(3 "B.Mask" user "Board Geometry/Soldermask Bottom")
		(17 "Dwgs.User" user "User.Drawings")
		(19 "Cmts.User" user "User.Comments")
		(21 "Eco1.User" user "User.Eco1")
		(23 "Eco2.User" user "User.Eco2")
		(25 "Edge.Cuts" user "Board Geometry/Outline")
		(27 "Margin" user)
		(31 "F.CrtYd" user "Package Geometry/Place Bound Top")
		(29 "B.CrtYd" user "Package Geometry/Place Bound Bottom")
		(35 "F.Fab" user "Ref Des/Assembly Top")
		(33 "B.Fab" user "Ref Des/Assembly Bottom")
	)
	(footprint ""
		(layer "B.Cu")
		(at 178.06035 -106.045 180)
		(property "Reference" "R164"
			(at 0 0 0)
			(layer "B.SilkS")
			(hide yes)
			(effects
				(font
					(size 1.27 1.27)
				)
				(justify mirror)
			)
		)
		(property "Value" ""
			(at 0 0 0)
			(layer "B.Fab")
			(effects
				(font
					(size 1.27 1.27)
				)
				(justify mirror)
			)
		)
		(duplicate_pad_numbers_are_jumpers no)
		(fp_line
			(start 0.7874 0.4064)
			(end 0.7874 -0.4064)
			(stroke
				(width 0.1524)
				(type default)
			)
			(layer "B.SilkS")
		)
		(fp_line
			(start 0.7874 -0.4064)
			(end -0.7874 -0.4064)
			(stroke
				(width 0.1524)
				(type default)
			)
			(layer "B.SilkS")
		)
		(fp_line
			(start -0.7874 0.4064)
			(end 0.7874 0.4064)
			(stroke
				(width 0.1524)
				(type default)
			)
			(layer "B.SilkS")
		)
		(fp_line
			(start -0.7874 -0.4064)
			(end -0.7874 0.4064)
			(stroke
				(width 0.1524)
				(type default)
			)
			(layer "B.SilkS")
		)
		(fp_line
			(start 0.67945 0.3048)
			(end 0.67945 -0.305054)
			(stroke
				(width 0.1)
				(type default)
			)
			(layer "B.Fab")
		)
		(fp_line
			(start 0.67945 -0.305054)
			(end 0.12065 -0.305054)
			(stroke
				(width 0.1)
				(type default)
			)
			(layer "B.Fab")
		)
		(fp_line
			(start 0.12065 0.3048)
			(end 0.67945 0.3048)
			(stroke
				(width 0.1)
				(type default)
			)
			(layer "B.Fab")
		)
		(fp_line
			(start 0.12065 0.2794)
			(end 0.12065 0.3048)
			(stroke
				(width 0.1)
				(type default)
			)
			(layer "B.Fab")
		)
		(fp_line
			(start 0.12065 -0.2794)
			(end -0.12065 -0.2794)
			(stroke
				(width 0.1)
				(type default)
			)
			(layer "B.Fab")
		)
		(fp_line
			(start 0.12065 -0.305054)
			(end 0.12065 -0.2794)
			(stroke
				(width 0.1)
				(type default)
			)
			(layer "B.Fab")
		)
		(fp_line
			(start -0.120396 0.3048)
			(end -0.120396 0.2794)
			(stroke
				(width 0.1)
				(type default)
			)
			(layer "B.Fab")
		)
		(fp_line
			(start -0.120396 0.2794)
			(end 0.12065 0.2794)
			(stroke
				(width 0.1)
				(type default)
			)
			(layer "B.Fab")
		)
		(fp_line
			(start -0.12065 -0.2794)
			(end -0.12065 -0.3048)
			(stroke
				(width 0.1)
				(type default)
			)
			(layer "B.Fab")
		)
		(fp_line
			(start -0.12065 -0.3048)
			(end -0.67945 -0.3048)
			(stroke
				(width 0.1)
				(type default)
			)
			(layer "B.Fab")
		)
		(fp_line
			(start -0.67945 0.3048)
			(end -0.120396 0.3048)
			(stroke
				(width 0.1)
				(type default)
			)
			(layer "B.Fab")
		)
		(fp_line
			(start -0.67945 -0.3048)
			(end -0.67945 0.3048)
			(stroke
				(width 0.1)
				(type default)
			)
			(layer "B.Fab")
		)
		(pad "1" smd circle
			(at 0.40005 0)
			(size 0 0)
			(layers "B.Cu" "B.Mask" "B.Paste")
			(net "PWRGD_DRAMPWRGD_CPU0_EF_R_LVC1")
		)
		(pad "2" smd circle
			(at -0.40005 0)
			(size 0 0)
			(layers "B.Cu" "B.Mask" "B.Paste")
			(net "PWRGD_DRAMPWRGD_CPU0_EF_LVC1_R2")
		)
	)
	(footprint ""
		(layer "B.Cu")
		(at 352.777298 -235.916724 180)
		(property "Reference" "C1"
			(at 0 0 0)
			(layer "B.SilkS")
			(hide yes)
			(effects
				(font
					(size 1.27 1.27)
				)
				(justify mirror)
			)
		)
		(property "Value" ""
			(at 0 0 0)
			(layer "B.Fab")
			(effects
				(font
					(size 1.27 1.27)
				)
				(justify mirror)
			)
		)
		(duplicate_pad_numbers_are_jumpers no)
		(fp_line
			(start 0.7874 0.4064)
			(end 0.7874 -0.4064)
			(stroke
				(width 0.1524)
				(type default)
			)
			(layer "B.SilkS")
		)
		(fp_line
			(start 0.7874 -0.4064)
			(end -0.7874 -0.4064)
			(stroke
				(width 0.1524)
				(type default)
			)
			(layer "B.SilkS")
		)
		(fp_line
			(start -0.7874 0.4064)
			(end 0.7874 0.4064)
			(stroke
				(width 0.1524)
				(type default)
			)
			(layer "B.SilkS")
		)
		(fp_line
			(start -0.7874 -0.4064)
			(end -0.7874 0.4064)
			(stroke
				(width 0.1524)
				(type default)
			)
			(layer "B.SilkS")
		)
		(fp_line
			(start 0.67945 0.3048)
			(end 0.67945 -0.305054)
			(stroke
				(width 0.1)
				(type default)
			)
			(layer "B.Fab")
		)
		(fp_line
			(start 0.67945 -0.305054)
			(end 0.12065 -0.305054)
			(stroke
				(width 0.1)
				(type default)
			)
			(layer "B.Fab")
		)
		(fp_line
			(start 0.12065 0.3048)
			(end 0.67945 0.3048)
			(stroke
				(width 0.1)
				(type default)
			)
			(layer "B.Fab")
		)
		(fp_line
			(start 0.12065 0.2794)
			(end 0.12065 0.3048)
			(stroke
				(width 0.1)
				(type default)
			)
			(layer "B.Fab")
		)
		(fp_line
			(start 0.12065 -0.2794)
			(end -0.12065 -0.2794)
			(stroke
				(width 0.1)
				(type default)
			)
			(layer "B.Fab")
		)
		(fp_line
			(start 0.12065 -0.305054)
			(end 0.12065 -0.2794)
			(stroke
				(width 0.1)
				(type default)
			)
			(layer "B.Fab")
		)
		(fp_line
			(start -0.120396 0.3048)
			(end -0.120396 0.2794)
			(stroke
				(width 0.1)
				(type default)
			)
			(layer "B.Fab")
		)
		(fp_line
			(start -0.120396 0.2794)
			(end 0.12065 0.2794)
			(stroke
				(width 0.1)
				(type default)
			)
			(layer "B.Fab")
		)
		(fp_line
			(start -0.12065 -0.2794)
			(end -0.12065 -0.3048)
			(stroke
				(width 0.1)
				(type default)
			)
			(layer "B.Fab")
		)
		(fp_line
			(start -0.12065 -0.3048)
			(end -0.67945 -0.3048)
			(stroke
				(width 0.1)
				(type default)
			)
			(layer "B.Fab")
		)
		(fp_line
			(start -0.67945 0.3048)
			(end -0.120396 0.3048)
			(stroke
				(width 0.1)
				(type default)
			)
			(layer "B.Fab")
		)
		(fp_line
			(start -0.67945 -0.3048)
			(end -0.67945 0.3048)
			(stroke
				(width 0.1)
				(type default)
			)
			(layer "B.Fab")
		)
		(pad "1" smd circle
			(at 0.40005 0)
			(size 0 0)
			(layers "B.Cu" "B.Mask" "B.Paste")
			(net "P3V3_AUX")
		)
		(pad "2" smd circle
			(at -0.40005 0)
			(size 0 0)
			(layers "B.Cu" "B.Mask" "B.Paste")
			(net "GND")
		)
	)
	(footprint ""
		(layer "B.Cu")
		(at 185.521346 -321.554856 -90)
		(property "Reference" "C89"
			(at 0 0 90)
			(layer "B.SilkS")
			(hide yes)
			(effects
				(font
					(size 1.27 1.27)
				)
				(justify mirror)
			)
		)
		(property "Value" ""
			(at 0 0 90)
			(layer "B.Fab")
			(effects
				(font
					(size 1.27 1.27)
				)
				(justify mirror)
			)
		)
		(duplicate_pad_numbers_are_jumpers no)
		(fp_line
			(start -1.524 0.762)
			(end 1.524 0.762)
			(stroke
				(width 0.1524)
				(type default)
			)
			(layer "B.SilkS")
		)
		(fp_line
			(start 1.524 0.762)
			(end 1.524 -0.762)
			(stroke
				(width 0.1524)
				(type default)
			)
			(layer "B.SilkS")
		)
		(fp_line
			(start -1.524 -0.762)
			(end -1.524 0.762)
			(stroke
				(width 0.1524)
				(type default)
			)
			(layer "B.SilkS")
		)
		(fp_line
			(start 1.524 -0.762)
			(end -1.524 -0.762)
			(stroke
				(width 0.1524)
				(type default)
			)
			(layer "B.SilkS")
		)
		(fp_line
			(start -1.1049 0.724916)
			(end -1.1049 -0.724916)
			(stroke
				(width 0.1)
				(type default)
			)
			(layer "B.Fab")
		)
		(fp_line
			(start 1.1049 0.724916)
			(end -1.1049 0.724916)
			(stroke
				(width 0.1)
				(type default)
			)
			(layer "B.Fab")
		)
		(fp_line
			(start -1.1049 -0.724916)
			(end 1.1049 -0.724916)
			(stroke
				(width 0.1)
				(type default)
			)
			(layer "B.Fab")
		)
		(fp_line
			(start 1.1049 -0.724916)
			(end 1.1049 0.724916)
			(stroke
				(width 0.1)
				(type default)
			)
			(layer "B.Fab")
		)
		(pad "1" smd rect
			(at 0.889 0 270)
			(size 1.016 1.27)
			(layers "B.Cu" "B.Mask" "B.Paste")
			(net "P12V_S3_AUX_CPU1_NVDIMM")
		)
		(pad "2" smd rect
			(at -0.889 0 270)
			(size 1.016 1.27)
			(layers "B.Cu" "B.Mask" "B.Paste")
			(net "GND")
		)
	)
)
